(kicad_pcb
	(version 20260206)
	(generator "pcbnew")
	(generator_version "10.0")
	(general
		(thickness 1.6)
		(legacy_teardrops no)
	)
	(paper "A4")
	(title_block
		(title "04192023_DAF0TMB3IC0_F0TG_MB_C_brd_V02_OCP.brd")
		(comment 1 "Grand Teton / footprints 422-428 of 8354")
	)
	(layers
		(0 "F.Cu" signal "TOP")
		(4 "In1.Cu" signal "GND")
		(6 "In2.Cu" signal "IN1")
		(8 "In3.Cu" signal "GND1")
		(10 "In4.Cu" signal "IN2")
		(12 "In5.Cu" signal "GND2")
		(14 "In6.Cu" signal "IN3")
		(16 "In7.Cu" signal "GND3")
		(18 "In8.Cu" signal "VCC")
		(20 "In9.Cu" signal "VCC1")
		(22 "In10.Cu" signal "GND4")
		(24 "In11.Cu" signal "IN4")
		(26 "In12.Cu" signal "GND5")
		(28 "In13.Cu" signal "IN5")
		(30 "In14.Cu" signal "GND6")
		(32 "In15.Cu" signal "IN6")
		(34 "In16.Cu" signal "GND7")
		(2 "B.Cu" signal "BOTTOM")
		(9 "F.Adhes" user "F.Adhesive")
		(11 "B.Adhes" user "B.Adhesive")
		(13 "F.Paste" user "Package Geometry/Pastemask Top")
		(15 "B.Paste" user "Package Geometry/Pastemask Bottom")
		(5 "F.SilkS" user "Ref Des/Silkscreen Top")
		(7 "B.SilkS" user "Ref Des/Silkscreen Bottom")
		(1 "F.Mask" user "Board Geometry/Soldermask Top")
		(3 "B.Mask" user "Board Geometry/Soldermask Bottom")
		(17 "Dwgs.User" user "User.Drawings")
		(19 "Cmts.User" user "User.Comments")
		(21 "Eco1.User" user "User.Eco1")
		(23 "Eco2.User" user "User.Eco2")
		(25 "Edge.Cuts" user "Board Geometry/Outline")
		(27 "Margin" user)
		(31 "F.CrtYd" user "Package Geometry/Place Bound Top")
		(29 "B.CrtYd" user "Package Geometry/Place Bound Bottom")
		(35 "F.Fab" user "Ref Des/Assembly Top")
		(33 "B.Fab" user "Ref Des/Assembly Bottom")
	)
	(footprint ""
		(layer "F.Cu")
		(at 144.690592 -107.683046 180)
		(property "Reference" "Q37"
			(at 0.715264 1.685036 0)
			(unlocked yes)
			(layer "F.SilkS")
			(effects
				(font
					(size 0.7874 0.5842)
					(thickness 0.1524)
				)
				(justify left)
			)
		)
		(property "Value" ""
			(at 0 0 180)
			(layer "F.Fab")
			(effects
				(font
					(size 1.27 1.27)
				)
			)
		)
		(duplicate_pad_numbers_are_jumpers no)
		(fp_line
			(start 1.332738 1.100074)
			(end -1.332738 1.100074)
			(stroke
				(width 0.1524)
				(type default)
			)
			(layer "F.SilkS")
		)
		(fp_line
			(start 1.332738 -1.100074)
			(end 1.332738 1.100074)
			(stroke
				(width 0.1524)
				(type default)
			)
			(layer "F.SilkS")
		)
		(fp_line
			(start 0.4826 -1.100074)
			(end 1.332738 -1.100074)
			(stroke
				(width 0.1524)
				(type default)
			)
			(layer "F.SilkS")
		)
		(fp_line
			(start 0 -0.541274)
			(end 0.4826 -1.100074)
			(stroke
				(width 0.1524)
				(type default)
			)
			(layer "F.SilkS")
		)
		(fp_line
			(start -0.4826 -1.100074)
			(end 0 -0.541274)
			(stroke
				(width 0.1524)
				(type default)
			)
			(layer "F.SilkS")
		)
		(fp_line
			(start -1.332738 1.100074)
			(end -1.332738 -1.100074)
			(stroke
				(width 0.1524)
				(type default)
			)
			(layer "F.SilkS")
		)
		(fp_line
			(start -1.332738 -1.100074)
			(end -0.4826 -1.100074)
			(stroke
				(width 0.1524)
				(type default)
			)
			(layer "F.SilkS")
		)
		(fp_poly
			(pts
				(xy -1.928876 -0.667512) (xy -2.630932 -0.316484) (xy -2.630932 -1.01854)
			)
			(stroke
				(width 0)
				(type default)
			)
			(fill yes)
			(layer "F.SilkS")
		)
		(fp_line
			(start 0.674878 1.100074)
			(end -0.674878 1.100074)
			(stroke
				(width 0.1)
				(type default)
			)
			(layer "F.Fab")
		)
		(fp_line
			(start 0.674878 -1.100074)
			(end 0.674878 1.100074)
			(stroke
				(width 0.1)
				(type default)
			)
			(layer "F.Fab")
		)
		(fp_line
			(start -0.674878 1.100074)
			(end -0.674878 -1.100074)
			(stroke
				(width 0.1)
				(type default)
			)
			(layer "F.Fab")
		)
		(fp_line
			(start -0.674878 -1.100074)
			(end 0.674878 -1.100074)
			(stroke
				(width 0.1)
				(type default)
			)
			(layer "F.Fab")
		)
		(fp_poly
			(pts
				(xy -2.2352 -0.298958) (xy -2.2352 -1.001014) (xy -1.533144 -0.649986)
			)
			(stroke
				(width 0)
				(type default)
			)
			(fill yes)
			(layer "F.Fab")
		)
		(pad "1" smd rect
			(at -0.94996 -0.649986 270)
			(size 0.4318 0.508)
			(layers "F.Cu" "F.Mask" "F.Paste")
			(net "GND")
		)
		(pad "2" smd rect
			(at -0.94996 0 270)
			(size 0.4318 0.508)
			(layers "F.Cu" "F.Mask" "F.Paste")
			(net "VR_P5V_EN")
		)
		(pad "3" smd rect
			(at -0.94996 0.649986 270)
			(size 0.4318 0.508)
			(layers "F.Cu" "F.Mask" "F.Paste")
			(net "VR_P5V_EN_D_R1")
		)
		(pad "4" smd rect
			(at 0.94996 0.649986 270)
			(size 0.4318 0.508)
			(layers "F.Cu" "F.Mask" "F.Paste")
			(net "GND")
		)
		(pad "5" smd rect
			(at 0.94996 0 270)
			(size 0.4318 0.508)
			(layers "F.Cu" "F.Mask" "F.Paste")
			(net "VR_P5V_EN_N")
		)
		(pad "6" smd rect
			(at 0.94996 -0.649986 270)
			(size 0.4318 0.508)
			(layers "F.Cu" "F.Mask" "F.Paste")
			(net "VR_P5V_EN_N")
		)
	)
	(footprint ""
		(layer "F.Cu")
		(at 402.253958 -324.862952 180)
		(property "Reference" "R461"
			(at 0 0 180)
			(layer "F.SilkS")
			(hide yes)
			(effects
				(font
					(size 1.27 1.27)
				)
			)
		)
		(property "Value" ""
			(at 0 0 180)
			(layer "F.Fab")
			(effects
				(font
					(size 1.27 1.27)
				)
			)
		)
		(duplicate_pad_numbers_are_jumpers no)
		(fp_line
			(start 0.7874 0.4064)
			(end -0.7874 0.4064)
			(stroke
				(width 0.1524)
				(type default)
			)
			(layer "F.SilkS")
		)
		(fp_line
			(start 0.7874 -0.4064)
			(end 0.7874 0.4064)
			(stroke
				(width 0.1524)
				(type default)
			)
			(layer "F.SilkS")
		)
		(fp_line
			(start -0.7874 0.4064)
			(end -0.7874 -0.4064)
			(stroke
				(width 0.1524)
				(type default)
			)
			(layer "F.SilkS")
		)
		(fp_line
			(start -0.7874 -0.4064)
			(end 0.7874 -0.4064)
			(stroke
				(width 0.1524)
				(type default)
			)
			(layer "F.SilkS")
		)
		(fp_line
			(start 0.67945 0.3048)
			(end 0.120396 0.3048)
			(stroke
				(width 0.1)
				(type default)
			)
			(layer "F.Fab")
		)
		(fp_line
			(start 0.67945 -0.3048)
			(end 0.67945 0.3048)
			(stroke
				(width 0.1)
				(type default)
			)
			(layer "F.Fab")
		)
		(fp_line
			(start 0.12065 -0.2794)
			(end 0.12065 -0.3048)
			(stroke
				(width 0.1)
				(type default)
			)
			(layer "F.Fab")
		)
		(fp_line
			(start 0.12065 -0.3048)
			(end 0.67945 -0.3048)
			(stroke
				(width 0.1)
				(type default)
			)
			(layer "F.Fab")
		)
		(fp_line
			(start 0.120396 0.3048)
			(end 0.120396 0.2794)
			(stroke
				(width 0.1)
				(type default)
			)
			(layer "F.Fab")
		)
		(fp_line
			(start 0.120396 0.2794)
			(end -0.12065 0.2794)
			(stroke
				(width 0.1)
				(type default)
			)
			(layer "F.Fab")
		)
		(fp_line
			(start -0.12065 0.3048)
			(end -0.67945 0.3048)
			(stroke
				(width 0.1)
				(type default)
			)
			(layer "F.Fab")
		)
		(fp_line
			(start -0.12065 0.2794)
			(end -0.12065 0.3048)
			(stroke
				(width 0.1)
				(type default)
			)
			(layer "F.Fab")
		)
		(fp_line
			(start -0.12065 -0.2794)
			(end 0.12065 -0.2794)
			(stroke
				(width 0.1)
				(type default)
			)
			(layer "F.Fab")
		)
		(fp_line
			(start -0.12065 -0.305054)
			(end -0.12065 -0.2794)
			(stroke
				(width 0.1)
				(type default)
			)
			(layer "F.Fab")
		)
		(fp_line
			(start -0.67945 0.3048)
			(end -0.67945 -0.305054)
			(stroke
				(width 0.1)
				(type default)
			)
			(layer "F.Fab")
		)
		(fp_line
			(start -0.67945 -0.305054)
			(end -0.12065 -0.305054)
			(stroke
				(width 0.1)
				(type default)
			)
			(layer "F.Fab")
		)
		(pad "1" smd circle
			(at -0.40005 0 180)
			(size 0 0)
			(layers "F.Cu" "F.Mask" "F.Paste")
			(net "SPI_CPU0_CLK")
		)
		(pad "2" smd circle
			(at 0.40005 0 180)
			(size 0 0)
			(layers "F.Cu" "F.Mask" "F.Paste")
			(net "SPI_CPU0_R_CLK")
		)
	)
	(footprint ""
		(layer "F.Cu")
		(at 432.151536 -101.97719)
		(property "Reference" "R3796"
			(at 0 0 0)
			(layer "F.SilkS")
			(hide yes)
			(effects
				(font
					(size 1.27 1.27)
				)
			)
		)
		(property "Value" ""
			(at 0 0 0)
			(layer "F.Fab")
			(effects
				(font
					(size 1.27 1.27)
				)
			)
		)
		(duplicate_pad_numbers_are_jumpers no)
		(fp_line
			(start -0.7874 -0.4064)
			(end 0.7874 -0.4064)
			(stroke
				(width 0.1524)
				(type default)
			)
			(layer "F.SilkS")
		)
		(fp_line
			(start -0.7874 0.4064)
			(end -0.7874 -0.4064)
			(stroke
				(width 0.1524)
				(type default)
			)
			(layer "F.SilkS")
		)
		(fp_line
			(start 0.7874 -0.4064)
			(end 0.7874 0.4064)
			(stroke
				(width 0.1524)
				(type default)
			)
			(layer "F.SilkS")
		)
		(fp_line
			(start 0.7874 0.4064)
			(end -0.7874 0.4064)
			(stroke
				(width 0.1524)
				(type default)
			)
			(layer "F.SilkS")
		)
		(fp_line
			(start -0.67945 -0.305054)
			(end -0.12065 -0.305054)
			(stroke
				(width 0.1)
				(type default)
			)
			(layer "F.Fab")
		)
		(fp_line
			(start -0.67945 0.3048)
			(end -0.67945 -0.305054)
			(stroke
				(width 0.1)
				(type default)
			)
			(layer "F.Fab")
		)
		(fp_line
			(start -0.12065 -0.305054)
			(end -0.12065 -0.2794)
			(stroke
				(width 0.1)
				(type default)
			)
			(layer "F.Fab")
		)
		(fp_line
			(start -0.12065 -0.2794)
			(end 0.12065 -0.2794)
			(stroke
				(width 0.1)
				(type default)
			)
			(layer "F.Fab")
		)
		(fp_line
			(start -0.12065 0.2794)
			(end -0.12065 0.3048)
			(stroke
				(width 0.1)
				(type default)
			)
			(layer "F.Fab")
		)
		(fp_line
			(start -0.12065 0.3048)
			(end -0.67945 0.3048)
			(stroke
				(width 0.1)
				(type default)
			)
			(layer "F.Fab")
		)
		(fp_line
			(start 0.120396 0.2794)
			(end -0.12065 0.2794)
			(stroke
				(width 0.1)
				(type default)
			)
			(layer "F.Fab")
		)
		(fp_line
			(start 0.120396 0.3048)
			(end 0.120396 0.2794)
			(stroke
				(width 0.1)
				(type default)
			)
			(layer "F.Fab")
		)
		(fp_line
			(start 0.12065 -0.3048)
			(end 0.67945 -0.3048)
			(stroke
				(width 0.1)
				(type default)
			)
			(layer "F.Fab")
		)
		(fp_line
			(start 0.12065 -0.2794)
			(end 0.12065 -0.3048)
			(stroke
				(width 0.1)
				(type default)
			)
			(layer "F.Fab")
		)
		(fp_line
			(start 0.67945 -0.3048)
			(end 0.67945 0.3048)
			(stroke
				(width 0.1)
				(type default)
			)
			(layer "F.Fab")
		)
		(fp_line
			(start 0.67945 0.3048)
			(end 0.120396 0.3048)
			(stroke
				(width 0.1)
				(type default)
			)
			(layer "F.Fab")
		)
		(pad "1" smd circle
			(at -0.40005 0)
			(size 0 0)
			(layers "F.Cu" "F.Mask" "F.Paste")
			(net "P3V3_AUX")
		)
		(pad "2" smd circle
			(at 0.40005 0)
			(size 0 0)
			(layers "F.Cu" "F.Mask" "F.Paste")
			(net "P3V3_OCP_FAULT_1")
		)
	)
	(footprint ""
		(layer "F.Cu")
		(at 117.895624 -255.555242 180)
		(property "Reference" "C2283"
			(at 0 0 180)
			(layer "F.SilkS")
			(hide yes)
			(effects
				(font
					(size 1.27 1.27)
				)
			)
		)
		(property "Value" ""
			(at 0 0 180)
			(layer "F.Fab")
			(effects
				(font
					(size 1.27 1.27)
				)
			)
		)
		(duplicate_pad_numbers_are_jumpers no)
		(fp_line
			(start 0.7874 0.4064)
			(end -0.7874 0.4064)
			(stroke
				(width 0.1524)
				(type default)
			)
			(layer "F.SilkS")
		)
		(fp_line
			(start 0.7874 -0.4064)
			(end 0.7874 0.4064)
			(stroke
				(width 0.1524)
				(type default)
			)
			(layer "F.SilkS")
		)
		(fp_line
			(start -0.7874 0.4064)
			(end -0.7874 -0.4064)
			(stroke
				(width 0.1524)
				(type default)
			)
			(layer "F.SilkS")
		)
		(fp_line
			(start -0.7874 -0.4064)
			(end 0.7874 -0.4064)
			(stroke
				(width 0.1524)
				(type default)
			)
			(layer "F.SilkS")
		)
		(fp_line
			(start 0.67945 0.3048)
			(end 0.120396 0.3048)
			(stroke
				(width 0.1)
				(type default)
			)
			(layer "F.Fab")
		)
		(fp_line
			(start 0.67945 -0.3048)
			(end 0.67945 0.3048)
			(stroke
				(width 0.1)
				(type default)
			)
			(layer "F.Fab")
		)
		(fp_line
			(start 0.12065 -0.2794)
			(end 0.12065 -0.3048)
			(stroke
				(width 0.1)
				(type default)
			)
			(layer "F.Fab")
		)
		(fp_line
			(start 0.12065 -0.3048)
			(end 0.67945 -0.3048)
			(stroke
				(width 0.1)
				(type default)
			)
			(layer "F.Fab")
		)
		(fp_line
			(start 0.120396 0.3048)
			(end 0.120396 0.2794)
			(stroke
				(width 0.1)
				(type default)
			)
			(layer "F.Fab")
		)
		(fp_line
			(start 0.120396 0.2794)
			(end -0.12065 0.2794)
			(stroke
				(width 0.1)
				(type default)
			)
			(layer "F.Fab")
		)
		(fp_line
			(start -0.12065 0.3048)
			(end -0.67945 0.3048)
			(stroke
				(width 0.1)
				(type default)
			)
			(layer "F.Fab")
		)
		(fp_line
			(start -0.12065 0.2794)
			(end -0.12065 0.3048)
			(stroke
				(width 0.1)
				(type default)
			)
			(layer "F.Fab")
		)
		(fp_line
			(start -0.12065 -0.2794)
			(end 0.12065 -0.2794)
			(stroke
				(width 0.1)
				(type default)
			)
			(layer "F.Fab")
		)
		(fp_line
			(start -0.12065 -0.305054)
			(end -0.12065 -0.2794)
			(stroke
				(width 0.1)
				(type default)
			)
			(layer "F.Fab")
		)
		(fp_line
			(start -0.67945 0.3048)
			(end -0.67945 -0.305054)
			(stroke
				(width 0.1)
				(type default)
			)
			(layer "F.Fab")
		)
		(fp_line
			(start -0.67945 -0.305054)
			(end -0.12065 -0.305054)
			(stroke
				(width 0.1)
				(type default)
			)
			(layer "F.Fab")
		)
		(pad "1" smd circle
			(at -0.40005 0 180)
			(size 0 0)
			(layers "F.Cu" "F.Mask" "F.Paste")
			(net "PVDDCR_SOC_P1")
		)
		(pad "2" smd circle
			(at 0.40005 0 180)
			(size 0 0)
			(layers "F.Cu" "F.Mask" "F.Paste")
			(net "GND")
		)
	)
	(footprint ""
		(layer "F.Cu")
		(at 368.600736 -402.548852 -90)
		(property "Reference" "R1091"
			(at 0 0 270)
			(layer "F.SilkS")
			(hide yes)
			(effects
				(font
					(size 1.27 1.27)
				)
			)
		)
		(property "Value" ""
			(at 0 0 270)
			(layer "F.Fab")
			(effects
				(font
					(size 1.27 1.27)
				)
			)
		)
		(duplicate_pad_numbers_are_jumpers no)
		(fp_line
			(start -0.32512 0.175006)
			(end -0.32512 -0.175006)
			(stroke
				(width 0.1)
				(type default)
			)
			(layer "F.Fab")
		)
		(fp_line
			(start 0.32512 0.175006)
			(end -0.32512 0.175006)
			(stroke
				(width 0.1)
				(type default)
			)
			(layer "F.Fab")
		)
		(fp_line
			(start -0.32512 -0.175006)
			(end 0.32512 -0.175006)
			(stroke
				(width 0.1)
				(type default)
			)
			(layer "F.Fab")
		)
		(fp_line
			(start 0.32512 -0.175006)
			(end 0.32512 0.175006)
			(stroke
				(width 0.1)
				(type default)
			)
			(layer "F.Fab")
		)
		(pad "1" smd rect
			(at -0.2667 0 270)
			(size 0.3048 0.381)
			(layers "F.Cu" "F.Mask" "F.Paste")
			(net "MODE_RT_CPU0_P3")
		)
		(pad "2" smd rect
			(at 0.2667 0 90)
			(size 0.3048 0.381)
			(layers "F.Cu" "F.Mask" "F.Paste")
			(net "GND")
		)
	)
	(footprint ""
		(layer "F.Cu")
		(at 147.199096 -66.337434)
		(property "Reference" "R8"
			(at 0 0 0)
			(layer "F.SilkS")
			(hide yes)
			(effects
				(font
					(size 1.27 1.27)
				)
			)
		)
		(property "Value" ""
			(at 0 0 0)
			(layer "F.Fab")
			(effects
				(font
					(size 1.27 1.27)
				)
			)
		)
		(duplicate_pad_numbers_are_jumpers no)
		(fp_line
			(start -0.7874 -0.4064)
			(end 0.7874 -0.4064)
			(stroke
				(width 0.1524)
				(type default)
			)
			(layer "F.SilkS")
		)
		(fp_line
			(start -0.7874 0.4064)
			(end -0.7874 -0.4064)
			(stroke
				(width 0.1524)
				(type default)
			)
			(layer "F.SilkS")
		)
		(fp_line
			(start 0.7874 -0.4064)
			(end 0.7874 0.4064)
			(stroke
				(width 0.1524)
				(type default)
			)
			(layer "F.SilkS")
		)
		(fp_line
			(start 0.7874 0.4064)
			(end -0.7874 0.4064)
			(stroke
				(width 0.1524)
				(type default)
			)
			(layer "F.SilkS")
		)
		(fp_line
			(start -0.67945 -0.305054)
			(end -0.12065 -0.305054)
			(stroke
				(width 0.1)
				(type default)
			)
			(layer "F.Fab")
		)
		(fp_line
			(start -0.67945 0.3048)
			(end -0.67945 -0.305054)
			(stroke
				(width 0.1)
				(type default)
			)
			(layer "F.Fab")
		)
		(fp_line
			(start -0.12065 -0.305054)
			(end -0.12065 -0.2794)
			(stroke
				(width 0.1)
				(type default)
			)
			(layer "F.Fab")
		)
		(fp_line
			(start -0.12065 -0.2794)
			(end 0.12065 -0.2794)
			(stroke
				(width 0.1)
				(type default)
			)
			(layer "F.Fab")
		)
		(fp_line
			(start -0.12065 0.2794)
			(end -0.12065 0.3048)
			(stroke
				(width 0.1)
				(type default)
			)
			(layer "F.Fab")
		)
		(fp_line
			(start -0.12065 0.3048)
			(end -0.67945 0.3048)
			(stroke
				(width 0.1)
				(type default)
			)
			(layer "F.Fab")
		)
		(fp_line
			(start 0.120396 0.2794)
			(end -0.12065 0.2794)
			(stroke
				(width 0.1)
				(type default)
			)
			(layer "F.Fab")
		)
		(fp_line
			(start 0.120396 0.3048)
			(end 0.120396 0.2794)
			(stroke
				(width 0.1)
				(type default)
			)
			(layer "F.Fab")
		)
		(fp_line
			(start 0.12065 -0.3048)
			(end 0.67945 -0.3048)
			(stroke
				(width 0.1)
				(type default)
			)
			(layer "F.Fab")
		)
		(fp_line
			(start 0.12065 -0.2794)
			(end 0.12065 -0.3048)
			(stroke
				(width 0.1)
				(type default)
			)
			(layer "F.Fab")
		)
		(fp_line
			(start 0.67945 -0.3048)
			(end 0.67945 0.3048)
			(stroke
				(width 0.1)
				(type default)
			)
			(layer "F.Fab")
		)
		(fp_line
			(start 0.67945 0.3048)
			(end 0.120396 0.3048)
			(stroke
				(width 0.1)
				(type default)
			)
			(layer "F.Fab")
		)
		(pad "1" smd circle
			(at -0.40005 0)
			(size 0 0)
			(layers "F.Cu" "F.Mask" "F.Paste")
			(net "GND")
		)
		(pad "2" smd circle
			(at 0.40005 0)
			(size 0 0)
			(layers "F.Cu" "F.Mask" "F.Paste")
			(net "JTAG_BMC_OE")
		)
	)
	(footprint ""
		(layer "F.Cu")
		(at 48.478694 -32.277558 90)
		(property "Reference" "C1825"
			(at 0 0 90)
			(layer "F.SilkS")
			(hide yes)
			(effects
				(font
					(size 1.27 1.27)
				)
			)
		)
		(property "Value" ""
			(at 0 0 90)
			(layer "F.Fab")
			(effects
				(font
					(size 1.27 1.27)
				)
			)
		)
		(duplicate_pad_numbers_are_jumpers no)
		(fp_line
			(start 0.7874 -0.4064)
			(end 0.7874 0.4064)
			(stroke
				(width 0.1524)
				(type default)
			)
			(layer "F.SilkS")
		)
		(fp_line
			(start -0.7874 -0.4064)
			(end 0.7874 -0.4064)
			(stroke
				(width 0.1524)
				(type default)
			)
			(layer "F.SilkS")
		)
		(fp_line
			(start 0.7874 0.4064)
			(end -0.7874 0.4064)
			(stroke
				(width 0.1524)
				(type default)
			)
			(layer "F.SilkS")
		)
		(fp_line
			(start -0.7874 0.4064)
			(end -0.7874 -0.4064)
			(stroke
				(width 0.1524)
				(type default)
			)
			(layer "F.SilkS")
		)
		(fp_line
			(start -0.12065 -0.305054)
			(end -0.12065 -0.2794)
			(stroke
				(width 0.1)
				(type default)
			)
			(layer "F.Fab")
		)
		(fp_line
			(start -0.67945 -0.305054)
			(end -0.12065 -0.305054)
			(stroke
				(width 0.1)
				(type default)
			)
			(layer "F.Fab")
		)
		(fp_line
			(start 0.67945 -0.3048)
			(end 0.67945 0.3048)
			(stroke
				(width 0.1)
				(type default)
			)
			(layer "F.Fab")
		)
		(fp_line
			(start 0.12065 -0.3048)
			(end 0.67945 -0.3048)
			(stroke
				(width 0.1)
				(type default)
			)
			(layer "F.Fab")
		)
		(fp_line
			(start 0.12065 -0.2794)
			(end 0.12065 -0.3048)
			(stroke
				(width 0.1)
				(type default)
			)
			(layer "F.Fab")
		)
		(fp_line
			(start -0.12065 -0.2794)
			(end 0.12065 -0.2794)
			(stroke
				(width 0.1)
				(type default)
			)
			(layer "F.Fab")
		)
		(fp_line
			(start 0.120396 0.2794)
			(end -0.12065 0.2794)
			(stroke
				(width 0.1)
				(type default)
			)
			(layer "F.Fab")
		)
		(fp_line
			(start -0.12065 0.2794)
			(end -0.12065 0.3048)
			(stroke
				(width 0.1)
				(type default)
			)
			(layer "F.Fab")
		)
		(fp_line
			(start 0.67945 0.3048)
			(end 0.120396 0.3048)
			(stroke
				(width 0.1)
				(type default)
			)
			(layer "F.Fab")
		)
		(fp_line
			(start 0.120396 0.3048)
			(end 0.120396 0.2794)
			(stroke
				(width 0.1)
				(type default)
			)
			(layer "F.Fab")
		)
		(fp_line
			(start -0.12065 0.3048)
			(end -0.67945 0.3048)
			(stroke
				(width 0.1)
				(type default)
			)
			(layer "F.Fab")
		)
		(fp_line
			(start -0.67945 0.3048)
			(end -0.67945 -0.305054)
			(stroke
				(width 0.1)
				(type default)
			)
			(layer "F.Fab")
		)
		(pad "1" smd circle
			(at -0.40005 0 90)
			(size 0 0)
			(layers "F.Cu" "F.Mask" "F.Paste")
			(net "P3V3_AUX")
		)
		(pad "2" smd circle
			(at 0.40005 0 90)
			(size 0 0)
			(layers "F.Cu" "F.Mask" "F.Paste")
			(net "GND")
		)
	)
)
